(kicad_pcb
	(version 20260206)
	(generator "pcbnew")
	(generator_version "10.0")
	(general
		(thickness 1.6)
		(legacy_teardrops no)
	)
	(paper "A4")
	(title_block
		(title "04192023_DAF0TMB3IC0_F0TG_MB_C_brd_V02_OCP.brd")
		(comment 1 "Grand Teton / footprints 6153-6158 of 8354")
	)
	(layers
		(0 "F.Cu" signal "TOP")
		(4 "In1.Cu" signal "GND")
		(6 "In2.Cu" signal "IN1")
		(8 "In3.Cu" signal "GND1")
		(10 "In4.Cu" signal "IN2")
		(12 "In5.Cu" signal "GND2")
		(14 "In6.Cu" signal "IN3")
		(16 "In7.Cu" signal "GND3")
		(18 "In8.Cu" signal "VCC")
		(20 "In9.Cu" signal "VCC1")
		(22 "In10.Cu" signal "GND4")
		(24 "In11.Cu" signal "IN4")
		(26 "In12.Cu" signal "GND5")
		(28 "In13.Cu" signal "IN5")
		(30 "In14.Cu" signal "GND6")
		(32 "In15.Cu" signal "IN6")
		(34 "In16.Cu" signal "GND7")
		(2 "B.Cu" signal "BOTTOM")
		(9 "F.Adhes" user "F.Adhesive")
		(11 "B.Adhes" user "B.Adhesive")
		(13 "F.Paste" user "Package Geometry/Pastemask Top")
		(15 "B.Paste" user "Package Geometry/Pastemask Bottom")
		(5 "F.SilkS" user "Ref Des/Silkscreen Top")
		(7 "B.SilkS" user "Ref Des/Silkscreen Bottom")
		(1 "F.Mask" user "Board Geometry/Soldermask Top")
		(3 "B.Mask" user "Board Geometry/Soldermask Bottom")
		(17 "Dwgs.User" user "User.Drawings")
		(19 "Cmts.User" user "User.Comments")
		(21 "Eco1.User" user "User.Eco1")
		(23 "Eco2.User" user "User.Eco2")
		(25 "Edge.Cuts" user "Board Geometry/Outline")
		(27 "Margin" user)
		(31 "F.CrtYd" user "Package Geometry/Place Bound Top")
		(29 "B.CrtYd" user "Package Geometry/Place Bound Bottom")
		(35 "F.Fab" user "Ref Des/Assembly Top")
		(33 "B.Fab" user "Ref Des/Assembly Bottom")
	)
	(footprint ""
		(layer "B.Cu")
		(at 431.918618 -344.006932 -90)
		(property "Reference" "PC226"
			(at 7.654036 -3.431286 270)
			(unlocked yes)
			(layer "B.SilkS")
			(effects
				(font
					(size 0.7874 0.5842)
					(thickness 0.1524)
				)
				(justify left mirror)
			)
		)
		(property "Value" ""
			(at 0 0 90)
			(layer "B.Fab")
			(effects
				(font
					(size 1.27 1.27)
				)
				(justify mirror)
			)
		)
		(duplicate_pad_numbers_are_jumpers no)
		(fp_line
			(start -4.533392 2.249932)
			(end 4.533392 2.249932)
			(stroke
				(width 0.1524)
				(type default)
			)
			(layer "B.SilkS")
		)
		(fp_line
			(start 4.533392 2.249932)
			(end 4.533392 -2.249932)
			(stroke
				(width 0.1524)
				(type default)
			)
			(layer "B.SilkS")
		)
		(fp_line
			(start -4.533392 -2.249932)
			(end -4.533392 2.249932)
			(stroke
				(width 0.1524)
				(type default)
			)
			(layer "B.SilkS")
		)
		(fp_line
			(start 4.533392 -2.249932)
			(end -4.533392 -2.249932)
			(stroke
				(width 0.1524)
				(type default)
			)
			(layer "B.SilkS")
		)
		(fp_rect
			(start 5.39242 2.326132)
			(end 4.533392 -2.326132)
			(stroke
				(width 0)
				(type default)
			)
			(fill yes)
			(layer "B.SilkS")
		)
		(fp_line
			(start -3.750056 2.249932)
			(end 3.750056 2.249932)
			(stroke
				(width 0.1)
				(type default)
			)
			(layer "B.Fab")
		)
		(fp_line
			(start 3.750056 2.249932)
			(end 3.750056 -2.249932)
			(stroke
				(width 0.1)
				(type default)
			)
			(layer "B.Fab")
		)
		(fp_line
			(start -3.750056 -2.249932)
			(end -3.750056 2.249932)
			(stroke
				(width 0.1)
				(type default)
			)
			(layer "B.Fab")
		)
		(fp_line
			(start 3.750056 -2.249932)
			(end -3.750056 -2.249932)
			(stroke
				(width 0.1)
				(type default)
			)
			(layer "B.Fab")
		)
		(fp_text user "-"
			(at -4.416806 2.466848 270)
			(unlocked yes)
			(layer "B.SilkS")
			(effects
				(font
					(size 1.905 1.4224)
					(thickness 0.1524)
				)
				(justify left mirror)
			)
		)
		(fp_text user "+"
			(at 6.934454 0.61595 180)
			(unlocked yes)
			(layer "B.SilkS")
			(effects
				(font
					(size 1.905 1.4224)
					(thickness 0.1524)
				)
				(justify left mirror)
			)
		)
		(fp_text user "+"
			(at 6.322314 0.786384 180)
			(unlocked yes)
			(layer "B.Fab")
			(effects
				(font
					(size 1.905 1.4224)
					(thickness 0.1524)
				)
				(justify left mirror)
			)
		)
		(fp_text user "-"
			(at -4.8514 -0.14605 270)
			(unlocked yes)
			(layer "B.Fab")
			(effects
				(font
					(size 1.905 1.4224)
					(thickness 0.1524)
				)
				(justify left mirror)
			)
		)
		(pad "1" smd rect
			(at 3.199892 0 90)
			(size 2.413 2.8194)
			(layers "B.Cu" "B.Mask" "B.Paste")
			(net "PVDD11_S3_P0")
		)
		(pad "2" smd rect
			(at -3.199892 0 90)
			(size 2.413 2.8194)
			(layers "B.Cu" "B.Mask" "B.Paste")
			(net "GND")
		)
	)
	(footprint ""
		(layer "B.Cu")
		(at 16.985234 -407.10866 -90)
		(property "Reference" "R656"
			(at 0 0 90)
			(layer "B.SilkS")
			(hide yes)
			(effects
				(font
					(size 1.27 1.27)
				)
				(justify mirror)
			)
		)
		(property "Value" ""
			(at 0 0 90)
			(layer "B.Fab")
			(effects
				(font
					(size 1.27 1.27)
				)
				(justify mirror)
			)
		)
		(duplicate_pad_numbers_are_jumpers no)
		(fp_line
			(start -0.7874 0.4064)
			(end 0.7874 0.4064)
			(stroke
				(width 0.1524)
				(type default)
			)
			(layer "B.SilkS")
		)
		(fp_line
			(start 0.7874 0.4064)
			(end 0.7874 -0.4064)
			(stroke
				(width 0.1524)
				(type default)
			)
			(layer "B.SilkS")
		)
		(fp_line
			(start -0.7874 -0.4064)
			(end -0.7874 0.4064)
			(stroke
				(width 0.1524)
				(type default)
			)
			(layer "B.SilkS")
		)
		(fp_line
			(start 0.7874 -0.4064)
			(end -0.7874 -0.4064)
			(stroke
				(width 0.1524)
				(type default)
			)
			(layer "B.SilkS")
		)
		(fp_line
			(start -0.67945 0.3048)
			(end -0.120396 0.3048)
			(stroke
				(width 0.1)
				(type default)
			)
			(layer "B.Fab")
		)
		(fp_line
			(start -0.120396 0.3048)
			(end -0.120396 0.2794)
			(stroke
				(width 0.1)
				(type default)
			)
			(layer "B.Fab")
		)
		(fp_line
			(start 0.12065 0.3048)
			(end 0.67945 0.3048)
			(stroke
				(width 0.1)
				(type default)
			)
			(layer "B.Fab")
		)
		(fp_line
			(start 0.67945 0.3048)
			(end 0.67945 -0.305054)
			(stroke
				(width 0.1)
				(type default)
			)
			(layer "B.Fab")
		)
		(fp_line
			(start -0.120396 0.2794)
			(end 0.12065 0.2794)
			(stroke
				(width 0.1)
				(type default)
			)
			(layer "B.Fab")
		)
		(fp_line
			(start 0.12065 0.2794)
			(end 0.12065 0.3048)
			(stroke
				(width 0.1)
				(type default)
			)
			(layer "B.Fab")
		)
		(fp_line
			(start -0.12065 -0.2794)
			(end -0.12065 -0.3048)
			(stroke
				(width 0.1)
				(type default)
			)
			(layer "B.Fab")
		)
		(fp_line
			(start 0.12065 -0.2794)
			(end -0.12065 -0.2794)
			(stroke
				(width 0.1)
				(type default)
			)
			(layer "B.Fab")
		)
		(fp_line
			(start -0.67945 -0.3048)
			(end -0.67945 0.3048)
			(stroke
				(width 0.1)
				(type default)
			)
			(layer "B.Fab")
		)
		(fp_line
			(start -0.12065 -0.3048)
			(end -0.67945 -0.3048)
			(stroke
				(width 0.1)
				(type default)
			)
			(layer "B.Fab")
		)
		(fp_line
			(start 0.12065 -0.305054)
			(end 0.12065 -0.2794)
			(stroke
				(width 0.1)
				(type default)
			)
			(layer "B.Fab")
		)
		(fp_line
			(start 0.67945 -0.305054)
			(end 0.12065 -0.305054)
			(stroke
				(width 0.1)
				(type default)
			)
			(layer "B.Fab")
		)
		(pad "1" smd circle
			(at 0.40005 0 90)
			(size 0 0)
			(layers "B.Cu" "B.Mask" "B.Paste")
			(net "P3V3_AUX")
		)
		(pad "2" smd circle
			(at -0.40005 0 90)
			(size 0 0)
			(layers "B.Cu" "B.Mask" "B.Paste")
			(net "PWRGD_P0V9_RETIMER_CPU1_R")
		)
	)
	(footprint ""
		(layer "B.Cu")
		(at 240.740692 -422.849548 90)
		(property "Reference" "C66"
			(at 0 0 90)
			(layer "B.SilkS")
			(hide yes)
			(effects
				(font
					(size 1.27 1.27)
				)
				(justify mirror)
			)
		)
		(property "Value" ""
			(at 0 0 90)
			(layer "B.Fab")
			(effects
				(font
					(size 1.27 1.27)
				)
				(justify mirror)
			)
		)
		(duplicate_pad_numbers_are_jumpers no)
		(fp_line
			(start 0.7874 -0.4064)
			(end -0.7874 -0.4064)
			(stroke
				(width 0.1524)
				(type default)
			)
			(layer "B.SilkS")
		)
		(fp_line
			(start -0.7874 -0.4064)
			(end -0.7874 0.4064)
			(stroke
				(width 0.1524)
				(type default)
			)
			(layer "B.SilkS")
		)
		(fp_line
			(start 0.7874 0.4064)
			(end 0.7874 -0.4064)
			(stroke
				(width 0.1524)
				(type default)
			)
			(layer "B.SilkS")
		)
		(fp_line
			(start -0.7874 0.4064)
			(end 0.7874 0.4064)
			(stroke
				(width 0.1524)
				(type default)
			)
			(layer "B.SilkS")
		)
		(fp_line
			(start 0.67945 -0.305054)
			(end 0.12065 -0.305054)
			(stroke
				(width 0.1)
				(type default)
			)
			(layer "B.Fab")
		)
		(fp_line
			(start 0.12065 -0.305054)
			(end 0.12065 -0.2794)
			(stroke
				(width 0.1)
				(type default)
			)
			(layer "B.Fab")
		)
		(fp_line
			(start -0.12065 -0.3048)
			(end -0.67945 -0.3048)
			(stroke
				(width 0.1)
				(type default)
			)
			(layer "B.Fab")
		)
		(fp_line
			(start -0.67945 -0.3048)
			(end -0.67945 0.3048)
			(stroke
				(width 0.1)
				(type default)
			)
			(layer "B.Fab")
		)
		(fp_line
			(start 0.12065 -0.2794)
			(end -0.12065 -0.2794)
			(stroke
				(width 0.1)
				(type default)
			)
			(layer "B.Fab")
		)
		(fp_line
			(start -0.12065 -0.2794)
			(end -0.12065 -0.3048)
			(stroke
				(width 0.1)
				(type default)
			)
			(layer "B.Fab")
		)
		(fp_line
			(start 0.12065 0.2794)
			(end 0.12065 0.3048)
			(stroke
				(width 0.1)
				(type default)
			)
			(layer "B.Fab")
		)
		(fp_line
			(start -0.120396 0.2794)
			(end 0.12065 0.2794)
			(stroke
				(width 0.1)
				(type default)
			)
			(layer "B.Fab")
		)
		(fp_line
			(start 0.67945 0.3048)
			(end 0.67945 -0.305054)
			(stroke
				(width 0.1)
				(type default)
			)
			(layer "B.Fab")
		)
		(fp_line
			(start 0.12065 0.3048)
			(end 0.67945 0.3048)
			(stroke
				(width 0.1)
				(type default)
			)
			(layer "B.Fab")
		)
		(fp_line
			(start -0.120396 0.3048)
			(end -0.120396 0.2794)
			(stroke
				(width 0.1)
				(type default)
			)
			(layer "B.Fab")
		)
		(fp_line
			(start -0.67945 0.3048)
			(end -0.120396 0.3048)
			(stroke
				(width 0.1)
				(type default)
			)
			(layer "B.Fab")
		)
		(pad "1" smd circle
			(at 0.40005 0 270)
			(size 0 0)
			(layers "B.Cu" "B.Mask" "B.Paste")
			(net "FM_FAN_PWR_EN_R")
		)
		(pad "2" smd circle
			(at -0.40005 0 270)
			(size 0 0)
			(layers "B.Cu" "B.Mask" "B.Paste")
			(net "GND")
		)
	)
	(footprint ""
		(layer "B.Cu")
		(at 111.781336 -254.448564 180)
		(property "Reference" "C2419"
			(at 0 0 0)
			(layer "B.SilkS")
			(hide yes)
			(effects
				(font
					(size 1.27 1.27)
				)
				(justify mirror)
			)
		)
		(property "Value" ""
			(at 0 0 0)
			(layer "B.Fab")
			(effects
				(font
					(size 1.27 1.27)
				)
				(justify mirror)
			)
		)
		(duplicate_pad_numbers_are_jumpers no)
		(fp_line
			(start 0.7874 0.4064)
			(end 0.7874 -0.4064)
			(stroke
				(width 0.1524)
				(type default)
			)
			(layer "B.SilkS")
		)
		(fp_line
			(start 0.7874 -0.4064)
			(end -0.7874 -0.4064)
			(stroke
				(width 0.1524)
				(type default)
			)
			(layer "B.SilkS")
		)
		(fp_line
			(start -0.7874 0.4064)
			(end 0.7874 0.4064)
			(stroke
				(width 0.1524)
				(type default)
			)
			(layer "B.SilkS")
		)
		(fp_line
			(start -0.7874 -0.4064)
			(end -0.7874 0.4064)
			(stroke
				(width 0.1524)
				(type default)
			)
			(layer "B.SilkS")
		)
		(fp_line
			(start 0.67945 0.3048)
			(end 0.67945 -0.305054)
			(stroke
				(width 0.1)
				(type default)
			)
			(layer "B.Fab")
		)
		(fp_line
			(start 0.67945 -0.305054)
			(end 0.12065 -0.305054)
			(stroke
				(width 0.1)
				(type default)
			)
			(layer "B.Fab")
		)
		(fp_line
			(start 0.12065 0.3048)
			(end 0.67945 0.3048)
			(stroke
				(width 0.1)
				(type default)
			)
			(layer "B.Fab")
		)
		(fp_line
			(start 0.12065 0.2794)
			(end 0.12065 0.3048)
			(stroke
				(width 0.1)
				(type default)
			)
			(layer "B.Fab")
		)
		(fp_line
			(start 0.12065 -0.2794)
			(end -0.12065 -0.2794)
			(stroke
				(width 0.1)
				(type default)
			)
			(layer "B.Fab")
		)
		(fp_line
			(start 0.12065 -0.305054)
			(end 0.12065 -0.2794)
			(stroke
				(width 0.1)
				(type default)
			)
			(layer "B.Fab")
		)
		(fp_line
			(start -0.120396 0.3048)
			(end -0.120396 0.2794)
			(stroke
				(width 0.1)
				(type default)
			)
			(layer "B.Fab")
		)
		(fp_line
			(start -0.120396 0.2794)
			(end 0.12065 0.2794)
			(stroke
				(width 0.1)
				(type default)
			)
			(layer "B.Fab")
		)
		(fp_line
			(start -0.12065 -0.2794)
			(end -0.12065 -0.3048)
			(stroke
				(width 0.1)
				(type default)
			)
			(layer "B.Fab")
		)
		(fp_line
			(start -0.12065 -0.3048)
			(end -0.67945 -0.3048)
			(stroke
				(width 0.1)
				(type default)
			)
			(layer "B.Fab")
		)
		(fp_line
			(start -0.67945 0.3048)
			(end -0.120396 0.3048)
			(stroke
				(width 0.1)
				(type default)
			)
			(layer "B.Fab")
		)
		(fp_line
			(start -0.67945 -0.3048)
			(end -0.67945 0.3048)
			(stroke
				(width 0.1)
				(type default)
			)
			(layer "B.Fab")
		)
		(pad "1" smd circle
			(at 0.40005 0)
			(size 0 0)
			(layers "B.Cu" "B.Mask" "B.Paste")
			(net "PVDDCR_SOC_P1")
		)
		(pad "2" smd circle
			(at -0.40005 0)
			(size 0 0)
			(layers "B.Cu" "B.Mask" "B.Paste")
			(net "GND")
		)
	)
	(footprint ""
		(layer "B.Cu")
		(at 110.527084 -261.748016 90)
		(property "Reference" "C2124"
			(at 0 0 90)
			(layer "B.SilkS")
			(hide yes)
			(effects
				(font
					(size 1.27 1.27)
				)
				(justify mirror)
			)
		)
		(property "Value" ""
			(at 0 0 90)
			(layer "B.Fab")
			(effects
				(font
					(size 1.27 1.27)
				)
				(justify mirror)
			)
		)
		(duplicate_pad_numbers_are_jumpers no)
		(fp_line
			(start 0.7874 -0.4064)
			(end -0.7874 -0.4064)
			(stroke
				(width 0.1524)
				(type default)
			)
			(layer "B.SilkS")
		)
		(fp_line
			(start -0.7874 -0.4064)
			(end -0.7874 0.4064)
			(stroke
				(width 0.1524)
				(type default)
			)
			(layer "B.SilkS")
		)
		(fp_line
			(start 0.7874 0.4064)
			(end 0.7874 -0.4064)
			(stroke
				(width 0.1524)
				(type default)
			)
			(layer "B.SilkS")
		)
		(fp_line
			(start -0.7874 0.4064)
			(end 0.7874 0.4064)
			(stroke
				(width 0.1524)
				(type default)
			)
			(layer "B.SilkS")
		)
		(fp_line
			(start 0.67945 -0.305054)
			(end 0.12065 -0.305054)
			(stroke
				(width 0.1)
				(type default)
			)
			(layer "B.Fab")
		)
		(fp_line
			(start 0.12065 -0.305054)
			(end 0.12065 -0.2794)
			(stroke
				(width 0.1)
				(type default)
			)
			(layer "B.Fab")
		)
		(fp_line
			(start -0.12065 -0.3048)
			(end -0.67945 -0.3048)
			(stroke
				(width 0.1)
				(type default)
			)
			(layer "B.Fab")
		)
		(fp_line
			(start -0.67945 -0.3048)
			(end -0.67945 0.3048)
			(stroke
				(width 0.1)
				(type default)
			)
			(layer "B.Fab")
		)
		(fp_line
			(start 0.12065 -0.2794)
			(end -0.12065 -0.2794)
			(stroke
				(width 0.1)
				(type default)
			)
			(layer "B.Fab")
		)
		(fp_line
			(start -0.12065 -0.2794)
			(end -0.12065 -0.3048)
			(stroke
				(width 0.1)
				(type default)
			)
			(layer "B.Fab")
		)
		(fp_line
			(start 0.12065 0.2794)
			(end 0.12065 0.3048)
			(stroke
				(width 0.1)
				(type default)
			)
			(layer "B.Fab")
		)
		(fp_line
			(start -0.120396 0.2794)
			(end 0.12065 0.2794)
			(stroke
				(width 0.1)
				(type default)
			)
			(layer "B.Fab")
		)
		(fp_line
			(start 0.67945 0.3048)
			(end 0.67945 -0.305054)
			(stroke
				(width 0.1)
				(type default)
			)
			(layer "B.Fab")
		)
		(fp_line
			(start 0.12065 0.3048)
			(end 0.67945 0.3048)
			(stroke
				(width 0.1)
				(type default)
			)
			(layer "B.Fab")
		)
		(fp_line
			(start -0.120396 0.3048)
			(end -0.120396 0.2794)
			(stroke
				(width 0.1)
				(type default)
			)
			(layer "B.Fab")
		)
		(fp_line
			(start -0.67945 0.3048)
			(end -0.120396 0.3048)
			(stroke
				(width 0.1)
				(type default)
			)
			(layer "B.Fab")
		)
		(pad "1" smd circle
			(at 0.40005 0 270)
			(size 0 0)
			(layers "B.Cu" "B.Mask" "B.Paste")
			(net "PVDD11_S3_P1")
		)
		(pad "2" smd circle
			(at -0.40005 0 270)
			(size 0 0)
			(layers "B.Cu" "B.Mask" "B.Paste")
			(net "GND")
		)
	)
	(footprint ""
		(layer "B.Cu")
		(at 126.276862 -164.133276 90)
		(property "Reference" "PR206"
			(at 0 0 90)
			(layer "B.SilkS")
			(hide yes)
			(effects
				(font
					(size 1.27 1.27)
				)
				(justify mirror)
			)
		)
		(property "Value" ""
			(at 0 0 90)
			(layer "B.Fab")
			(effects
				(font
					(size 1.27 1.27)
				)
				(justify mirror)
			)
		)
		(duplicate_pad_numbers_are_jumpers no)
		(fp_line
			(start 0.7874 -0.4064)
			(end -0.7874 -0.4064)
			(stroke
				(width 0.1524)
				(type default)
			)
			(layer "B.SilkS")
		)
		(fp_line
			(start -0.7874 -0.4064)
			(end -0.7874 0.4064)
			(stroke
				(width 0.1524)
				(type default)
			)
			(layer "B.SilkS")
		)
		(fp_line
			(start 0.7874 0.4064)
			(end 0.7874 -0.4064)
			(stroke
				(width 0.1524)
				(type default)
			)
			(layer "B.SilkS")
		)
		(fp_line
			(start -0.7874 0.4064)
			(end 0.7874 0.4064)
			(stroke
				(width 0.1524)
				(type default)
			)
			(layer "B.SilkS")
		)
		(fp_line
			(start 0.67945 -0.305054)
			(end 0.12065 -0.305054)
			(stroke
				(width 0.1)
				(type default)
			)
			(layer "B.Fab")
		)
		(fp_line
			(start 0.12065 -0.305054)
			(end 0.12065 -0.2794)
			(stroke
				(width 0.1)
				(type default)
			)
			(layer "B.Fab")
		)
		(fp_line
			(start -0.12065 -0.3048)
			(end -0.67945 -0.3048)
			(stroke
				(width 0.1)
				(type default)
			)
			(layer "B.Fab")
		)
		(fp_line
			(start -0.67945 -0.3048)
			(end -0.67945 0.3048)
			(stroke
				(width 0.1)
				(type default)
			)
			(layer "B.Fab")
		)
		(fp_line
			(start 0.12065 -0.2794)
			(end -0.12065 -0.2794)
			(stroke
				(width 0.1)
				(type default)
			)
			(layer "B.Fab")
		)
		(fp_line
			(start -0.12065 -0.2794)
			(end -0.12065 -0.3048)
			(stroke
				(width 0.1)
				(type default)
			)
			(layer "B.Fab")
		)
		(fp_line
			(start 0.12065 0.2794)
			(end 0.12065 0.3048)
			(stroke
				(width 0.1)
				(type default)
			)
			(layer "B.Fab")
		)
		(fp_line
			(start -0.120396 0.2794)
			(end 0.12065 0.2794)
			(stroke
				(width 0.1)
				(type default)
			)
			(layer "B.Fab")
		)
		(fp_line
			(start 0.67945 0.3048)
			(end 0.67945 -0.305054)
			(stroke
				(width 0.1)
				(type default)
			)
			(layer "B.Fab")
		)
		(fp_line
			(start 0.12065 0.3048)
			(end 0.67945 0.3048)
			(stroke
				(width 0.1)
				(type default)
			)
			(layer "B.Fab")
		)
		(fp_line
			(start -0.120396 0.3048)
			(end -0.120396 0.2794)
			(stroke
				(width 0.1)
				(type default)
			)
			(layer "B.Fab")
		)
		(fp_line
			(start -0.67945 0.3048)
			(end -0.120396 0.3048)
			(stroke
				(width 0.1)
				(type default)
			)
			(layer "B.Fab")
		)
		(pad "1" smd circle
			(at 0.40005 0 270)
			(size 0 0)
			(layers "B.Cu" "B.Mask" "B.Paste")
			(net "PVDDCR_CPU0_P1_PVCC")
		)
		(pad "2" smd circle
			(at -0.40005 0 270)
			(size 0 0)
			(layers "B.Cu" "B.Mask" "B.Paste")
			(net "PVDDCR_SOC_P1_VCC2")
		)
	)
)
